(kicad_pcb
	(version 20260206)
	(generator "pcbnew")
	(generator_version "10.0")
	(general
		(thickness 1.6)
		(legacy_teardrops no)
	)
	(paper "A4")
	(title_block
		(title "Bryce Canyon_F.DPB_16315-1-OCP.brd")
		(comment 1 "Bryce Canyon / footprints 1571-1575 of 2223")
	)
	(layers
		(0 "F.Cu" signal "TOP")
		(4 "In1.Cu" signal "L2GND")
		(6 "In2.Cu" signal "L3")
		(8 "In3.Cu" signal "L4GND")
		(10 "In4.Cu" signal "L5")
		(12 "In5.Cu" signal "L6VCC")
		(14 "In6.Cu" signal "L7VCC")
		(16 "In7.Cu" signal "L8")
		(18 "In8.Cu" signal "L9GND")
		(20 "In9.Cu" signal "L10")
		(22 "In10.Cu" signal "L11GND")
		(2 "B.Cu" signal "BOTTOM")
		(9 "F.Adhes" user "F.Adhesive")
		(11 "B.Adhes" user "B.Adhesive")
		(13 "F.Paste" user "Package Geometry/Pastemask Top")
		(15 "B.Paste" user "Package Geometry/Pastemask Bottom")
		(5 "F.SilkS" user "Ref Des/Silkscreen Top")
		(7 "B.SilkS" user "Ref Des/Silkscreen Bottom")
		(1 "F.Mask" user "Board Geometry/Soldermask Top")
		(3 "B.Mask" user "Board Geometry/Soldermask Bottom")
		(17 "Dwgs.User" user "User.Drawings")
		(19 "Cmts.User" user "User.Comments")
		(21 "Eco1.User" user "User.Eco1")
		(23 "Eco2.User" user "User.Eco2")
		(25 "Edge.Cuts" user "Board Geometry/Outline")
		(27 "Margin" user)
		(31 "F.CrtYd" user "Package Geometry/Place Bound Top")
		(29 "B.CrtYd" user "Package Geometry/Place Bound Bottom")
		(35 "F.Fab" user "Ref Des/Assembly Top")
		(33 "B.Fab" user "Ref Des/Assembly Bottom")
	)
	(footprint ""
		(layer "F.Cu")
		(at 32.020002 -248.11355)
		(property "Reference" "R1209"
			(at 0 0 0)
			(layer "F.SilkS")
			(hide yes)
			(effects
				(font
					(size 1.27 1.27)
				)
			)
		)
		(property "Value" "0R3J-0-U-GP"
			(at -0.0254 -2.5146 0)
			(unlocked yes)
			(layer "F.Fab")
			(hide yes)
			(effects
				(font
					(size 1.016 1.016)
					(thickness 0.1524)
				)
			)
		)
		(property "Device Type" "R603H22"
			(at -0.0254 -4.0386 0)
			(unlocked yes)
			(layer "F.Fab")
			(hide yes)
			(effects
				(font
					(size 1.016 1.016)
					(thickness 0.1524)
				)
			)
		)
		(duplicate_pad_numbers_are_jumpers no)
		(fp_line
			(start -0.4826 0)
			(end -0.2032 0)
			(stroke
				(width 0.2032)
				(type default)
			)
			(layer "F.SilkS")
		)
		(fp_line
			(start 0.2032 0)
			(end 0.4826 0)
			(stroke
				(width 0.2032)
				(type default)
			)
			(layer "F.SilkS")
		)
		(fp_rect
			(start -0.5842 1.3335)
			(end 0.5842 -1.3335)
			(stroke
				(width 0)
				(type default)
			)
			(fill no)
			(layer "F.CrtYd")
		)
		(fp_rect
			(start -0.5842 1.3335)
			(end 0.5842 -1.3335)
			(stroke
				(width 0)
				(type default)
			)
			(fill no)
			(layer "F.Fab")
		)
		(pad "1" smd custom
			(at 0 -0.762)
			(size 0.2159 0.2159)
			(layers "F.Cu" "F.Mask" "F.Paste")
			(net "P5V_A_VBST")
			(options
				(clearance outline)
				(anchor circle)
			)
			(primitives
				(gr_poly
					(pts
						(arc
							(start -0.3302 -0.4318)
							(mid -0.402042 -0.402042)
							(end -0.4318 -0.3302)
						)
						(arc
							(start -0.4318 0.3302)
							(mid -0.402042 0.402042)
							(end -0.3302 0.4318)
						)
						(arc
							(start 0.3302 0.4318)
							(mid 0.402042 0.402042)
							(end 0.4318 0.3302)
						)
						(arc
							(start 0.4318 -0.3302)
							(mid 0.402042 -0.402042)
							(end 0.3302 -0.4318)
						)
					)
					(width 0)
					(fill yes)
				)
			)
		)
		(pad "2" smd custom
			(at 0 0.762)
			(size 0.2159 0.2159)
			(layers "F.Cu" "F.Mask" "F.Paste")
			(net "P5V_A_VBST_RC")
			(options
				(clearance outline)
				(anchor circle)
			)
			(primitives
				(gr_poly
					(pts
						(arc
							(start -0.3302 -0.4318)
							(mid -0.402042 -0.402042)
							(end -0.4318 -0.3302)
						)
						(arc
							(start -0.4318 0.3302)
							(mid -0.402042 0.402042)
							(end -0.3302 0.4318)
						)
						(arc
							(start 0.3302 0.4318)
							(mid 0.402042 0.402042)
							(end 0.4318 0.3302)
						)
						(arc
							(start 0.4318 -0.3302)
							(mid 0.402042 -0.402042)
							(end 0.3302 -0.4318)
						)
					)
					(width 0)
					(fill yes)
				)
			)
		)
	)
	(footprint ""
		(layer "F.Cu")
		(at 155.42514 -143.325596 180)
		(property "Reference" "R1065"
			(at 0 0 180)
			(layer "F.SilkS")
			(hide yes)
			(effects
				(font
					(size 1.27 1.27)
				)
			)
		)
		(property "Value" "3K92R2F-GP"
			(at 0.064008 -3.993896 180)
			(unlocked yes)
			(layer "F.Fab")
			(hide yes)
			(effects
				(font
					(size 1.016 1.016)
					(thickness 0.1524)
				)
			)
		)
		(property "Device Type" "R402H16"
			(at 0.064008 -5.517896 180)
			(unlocked yes)
			(layer "F.Fab")
			(hide yes)
			(effects
				(font
					(size 1.016 1.016)
					(thickness 0.1524)
				)
			)
		)
		(duplicate_pad_numbers_are_jumpers no)
		(fp_line
			(start 0.508 -0.9398)
			(end -0.508 -0.9398)
			(stroke
				(width 0.1524)
				(type default)
			)
			(layer "F.SilkS")
		)
		(fp_line
			(start -0.508 -0.9398)
			(end -0.508 0.9398)
			(stroke
				(width 0.1524)
				(type default)
			)
			(layer "F.SilkS")
		)
		(fp_rect
			(start -0.508 0.9398)
			(end 0.508 -0.9398)
			(stroke
				(width 0)
				(type default)
			)
			(fill no)
			(layer "F.CrtYd")
		)
		(fp_rect
			(start -0.508 0.9398)
			(end 0.508 -0.9398)
			(stroke
				(width 0)
				(type default)
			)
			(fill no)
			(layer "F.Fab")
		)
		(pad "1" smd custom
			(at 0 -0.4445 180)
			(size 0.1397 0.1397)
			(layers "F.Cu" "F.Mask" "F.Paste")
			(net "MB0_CM_OV_R")
			(options
				(clearance outline)
				(anchor circle)
			)
			(primitives
				(gr_poly
					(pts
						(arc
							(start -0.1778 -0.2794)
							(mid -0.249642 -0.249642)
							(end -0.2794 -0.1778)
						)
						(arc
							(start -0.2794 0.1778)
							(mid -0.249642 0.249642)
							(end -0.1778 0.2794)
						)
						(arc
							(start 0.1778 0.2794)
							(mid 0.249642 0.249642)
							(end 0.2794 0.1778)
						)
						(arc
							(start 0.2794 -0.1778)
							(mid 0.249642 -0.249642)
							(end 0.1778 -0.2794)
						)
					)
					(width 0)
					(fill yes)
				)
			)
		)
		(pad "2" smd custom
			(at 0 0.4445 180)
			(size 0.1397 0.1397)
			(layers "F.Cu" "F.Mask" "F.Paste")
			(net "AGND_CURRENT_MONOA")
			(options
				(clearance outline)
				(anchor circle)
			)
			(primitives
				(gr_poly
					(pts
						(arc
							(start -0.1778 -0.2794)
							(mid -0.249642 -0.249642)
							(end -0.2794 -0.1778)
						)
						(arc
							(start -0.2794 0.1778)
							(mid -0.249642 0.249642)
							(end -0.1778 0.2794)
						)
						(arc
							(start 0.1778 0.2794)
							(mid 0.249642 0.249642)
							(end 0.2794 0.1778)
						)
						(arc
							(start 0.2794 -0.1778)
							(mid 0.249642 -0.249642)
							(end 0.1778 -0.2794)
						)
					)
					(width 0)
					(fill yes)
				)
			)
		)
	)
	(footprint ""
		(layer "F.Cu")
		(at 439.8391 -158.939992 90)
		(property "Reference" "VIA12"
			(at 0 0 90)
			(layer "F.SilkS")
			(hide yes)
			(effects
				(font
					(size 1.27 1.27)
				)
			)
		)
		(property "Value" "100OHM-8L-1D6MM-L18L16-GP"
			(at -3.7211 -4.5085 90)
			(unlocked yes)
			(layer "F.Fab")
			(hide yes)
			(effects
				(font
					(size 1.016 1.016)
					(thickness 0.1524)
				)
			)
		)
		(property "Device Type" "VIA-PCIE-4P-394076"
			(at -3.7211 -6.0325 90)
			(unlocked yes)
			(layer "F.Fab")
			(hide yes)
			(effects
				(font
					(size 1.016 1.016)
					(thickness 0.1524)
				)
			)
		)
		(duplicate_pad_numbers_are_jumpers no)
		(fp_rect
			(start -1.9685 0.381)
			(end 1.9685 -0.381)
			(stroke
				(width 0)
				(type default)
			)
			(fill no)
			(layer "F.CrtYd")
		)
		(fp_rect
			(start -1.9685 0.381)
			(end 1.9685 -0.381)
			(stroke
				(width 0)
				(type default)
			)
			(fill no)
			(layer "F.Fab")
		)
		(pad "1" thru_hole circle
			(at -1.5875 0 90)
			(size 0.508 0.508)
			(drill 0.254)
			(layers "*.Cu" "*.Mask")
			(remove_unused_layers no)
			(net "GND")
			(clearance 0.127)
			(thermal_gap 0.127)
		)
		(pad "2" thru_hole circle
			(at -0.5715 0 90)
			(size 0.508 0.508)
			(drill 0.254)
			(layers "*.Cu" "*.Mask")
			(remove_unused_layers no)
			(net "PHY_SCC_A_TO_DRV_A_22_DP")
			(clearance 0.127)
			(thermal_gap 0.127)
		)
		(pad "3" thru_hole circle
			(at 0.5715 0 90)
			(size 0.508 0.508)
			(drill 0.254)
			(layers "*.Cu" "*.Mask")
			(remove_unused_layers no)
			(net "PHY_SCC_A_TO_DRV_A_22_DN")
			(clearance 0.127)
			(thermal_gap 0.127)
		)
		(pad "4" thru_hole circle
			(at 1.5875 0 90)
			(size 0.508 0.508)
			(drill 0.254)
			(layers "*.Cu" "*.Mask")
			(remove_unused_layers no)
			(net "GND")
			(clearance 0.127)
			(thermal_gap 0.127)
		)
	)
	(footprint ""
		(layer "F.Cu")
		(at 302.039528 -63.4492 90)
		(property "Reference" "R642"
			(at 0 0 90)
			(layer "F.SilkS")
			(hide yes)
			(effects
				(font
					(size 1.27 1.27)
				)
			)
		)
		(property "Value" "0R2J-2-GP"
			(at 0.064008 -3.993896 90)
			(unlocked yes)
			(layer "F.Fab")
			(hide yes)
			(effects
				(font
					(size 1.016 1.016)
					(thickness 0.1524)
				)
			)
		)
		(property "Device Type" "R402H16"
			(at 0.064008 -5.517896 90)
			(unlocked yes)
			(layer "F.Fab")
			(hide yes)
			(effects
				(font
					(size 1.016 1.016)
					(thickness 0.1524)
				)
			)
		)
		(duplicate_pad_numbers_are_jumpers no)
		(fp_line
			(start 0.508 -0.9398)
			(end -0.508 -0.9398)
			(stroke
				(width 0.1524)
				(type default)
			)
			(layer "F.SilkS")
		)
		(fp_line
			(start -0.508 -0.9398)
			(end -0.508 0.9398)
			(stroke
				(width 0.1524)
				(type default)
			)
			(layer "F.SilkS")
		)
		(fp_rect
			(start -0.508 0.9398)
			(end 0.508 -0.9398)
			(stroke
				(width 0)
				(type default)
			)
			(fill no)
			(layer "F.CrtYd")
		)
		(fp_rect
			(start -0.508 0.9398)
			(end 0.508 -0.9398)
			(stroke
				(width 0)
				(type default)
			)
			(fill no)
			(layer "F.Fab")
		)
		(pad "1" smd custom
			(at 0 -0.4445 90)
			(size 0.1397 0.1397)
			(layers "F.Cu" "F.Mask" "F.Paste")
			(net "I2C_BMC_B_COMP_B_SDA_R")
			(options
				(clearance outline)
				(anchor circle)
			)
			(primitives
				(gr_poly
					(pts
						(arc
							(start -0.1778 -0.2794)
							(mid -0.249642 -0.249642)
							(end -0.2794 -0.1778)
						)
						(arc
							(start -0.2794 0.1778)
							(mid -0.249642 0.249642)
							(end -0.1778 0.2794)
						)
						(arc
							(start 0.1778 0.2794)
							(mid 0.249642 0.249642)
							(end 0.2794 0.1778)
						)
						(arc
							(start 0.2794 -0.1778)
							(mid 0.249642 -0.249642)
							(end 0.1778 -0.2794)
						)
					)
					(width 0)
					(fill yes)
				)
			)
		)
		(pad "2" smd custom
			(at 0 0.4445 90)
			(size 0.1397 0.1397)
			(layers "F.Cu" "F.Mask" "F.Paste")
			(net "I2C_BMC_B_COMP_B_SDA_BUF")
			(options
				(clearance outline)
				(anchor circle)
			)
			(primitives
				(gr_poly
					(pts
						(arc
							(start -0.1778 -0.2794)
							(mid -0.249642 -0.249642)
							(end -0.2794 -0.1778)
						)
						(arc
							(start -0.2794 0.1778)
							(mid -0.249642 0.249642)
							(end -0.1778 0.2794)
						)
						(arc
							(start 0.1778 0.2794)
							(mid 0.249642 0.249642)
							(end 0.2794 0.1778)
						)
						(arc
							(start 0.2794 -0.1778)
							(mid 0.249642 -0.249642)
							(end 0.1778 -0.2794)
						)
					)
					(width 0)
					(fill yes)
				)
			)
		)
	)
	(footprint ""
		(layer "F.Cu")
		(at 373.5578 -133.8834)
		(property "Reference" "R1074"
			(at 0 0 0)
			(layer "F.SilkS")
			(hide yes)
			(effects
				(font
					(size 1.27 1.27)
				)
			)
		)
		(property "Value" "0R2J-2-GP"
			(at 0.064008 -3.993896 0)
			(unlocked yes)
			(layer "F.Fab")
			(hide yes)
			(effects
				(font
					(size 1.016 1.016)
					(thickness 0.1524)
				)
			)
		)
		(property "Device Type" "R402H16"
			(at 0.064008 -5.517896 0)
			(unlocked yes)
			(layer "F.Fab")
			(hide yes)
			(effects
				(font
					(size 1.016 1.016)
					(thickness 0.1524)
				)
			)
		)
		(duplicate_pad_numbers_are_jumpers no)
		(fp_line
			(start -0.508 -0.9398)
			(end -0.508 0.9398)
			(stroke
				(width 0.1524)
				(type default)
			)
			(layer "F.SilkS")
		)
		(fp_line
			(start 0.508 -0.9398)
			(end -0.508 -0.9398)
			(stroke
				(width 0.1524)
				(type default)
			)
			(layer "F.SilkS")
		)
		(fp_rect
			(start -0.508 0.9398)
			(end 0.508 -0.9398)
			(stroke
				(width 0)
				(type default)
			)
			(fill no)
			(layer "F.CrtYd")
		)
		(fp_rect
			(start -0.508 0.9398)
			(end 0.508 -0.9398)
			(stroke
				(width 0)
				(type default)
			)
			(fill no)
			(layer "F.Fab")
		)
		(pad "1" smd custom
			(at 0 -0.4445)
			(size 0.1397 0.1397)
			(layers "F.Cu" "F.Mask" "F.Paste")
			(net "MB1_CM_ADR1_R")
			(options
				(clearance outline)
				(anchor circle)
			)
			(primitives
				(gr_poly
					(pts
						(arc
							(start -0.1778 -0.2794)
							(mid -0.249642 -0.249642)
							(end -0.2794 -0.1778)
						)
						(arc
							(start -0.2794 0.1778)
							(mid -0.249642 0.249642)
							(end -0.1778 0.2794)
						)
						(arc
							(start 0.1778 0.2794)
							(mid 0.249642 0.249642)
							(end 0.2794 0.1778)
						)
						(arc
							(start 0.2794 -0.1778)
							(mid 0.249642 -0.249642)
							(end 0.1778 -0.2794)
						)
					)
					(width 0)
					(fill yes)
				)
			)
		)
		(pad "2" smd custom
			(at 0 0.4445)
			(size 0.1397 0.1397)
			(layers "F.Cu" "F.Mask" "F.Paste")
			(net "AGND_CURRENT_MONOB")
			(options
				(clearance outline)
				(anchor circle)
			)
			(primitives
				(gr_poly
					(pts
						(arc
							(start -0.1778 -0.2794)
							(mid -0.249642 -0.249642)
							(end -0.2794 -0.1778)
						)
						(arc
							(start -0.2794 0.1778)
							(mid -0.249642 0.249642)
							(end -0.1778 0.2794)
						)
						(arc
							(start 0.1778 0.2794)
							(mid 0.249642 0.249642)
							(end 0.2794 0.1778)
						)
						(arc
							(start 0.2794 -0.1778)
							(mid 0.249642 -0.249642)
							(end 0.1778 -0.2794)
						)
					)
					(width 0)
					(fill yes)
				)
			)
		)
	)
)
